(kicad_pcb
	(version 20260206)
	(generator "pcbnew")
	(generator_version "10.0")
	(general
		(thickness 1.6)
		(legacy_teardrops no)
	)
	(paper "A4")
	(title_block
		(title "01162023_DA0F0TEBIF0_F0T_Expander_BD_F_brd_V02_OCP.brd")
		(comment 1 "Grand Teton / footprints 1188-1194 of 9728")
	)
	(layers
		(0 "F.Cu" signal "TOP")
		(4 "In1.Cu" signal "GND")
		(6 "In2.Cu" signal "VCC")
		(8 "In3.Cu" signal "VCC1")
		(10 "In4.Cu" signal "GND1")
		(12 "In5.Cu" signal "IN1")
		(14 "In6.Cu" signal "GND2")
		(16 "In7.Cu" signal "IN2")
		(18 "In8.Cu" signal "GND3")
		(20 "In9.Cu" signal "IN3")
		(22 "In10.Cu" signal "GND4")
		(24 "In11.Cu" signal "IN4")
		(26 "In12.Cu" signal "GND5")
		(28 "In13.Cu" signal "IN5")
		(30 "In14.Cu" signal "GND6")
		(32 "In15.Cu" signal "IN6")
		(34 "In16.Cu" signal "GND7")
		(2 "B.Cu" signal "BOTTOM")
		(9 "F.Adhes" user "F.Adhesive")
		(11 "B.Adhes" user "B.Adhesive")
		(13 "F.Paste" user "Package Geometry/Pastemask Top")
		(15 "B.Paste" user "Package Geometry/Pastemask Bottom")
		(5 "F.SilkS" user "Ref Des/Silkscreen Top")
		(7 "B.SilkS" user "Ref Des/Silkscreen Bottom")
		(1 "F.Mask" user "Board Geometry/Soldermask Top")
		(3 "B.Mask" user "Board Geometry/Soldermask Bottom")
		(17 "Dwgs.User" user "User.Drawings")
		(19 "Cmts.User" user "User.Comments")
		(21 "Eco1.User" user "User.Eco1")
		(23 "Eco2.User" user "User.Eco2")
		(25 "Edge.Cuts" user "Board Geometry/Outline")
		(27 "Margin" user)
		(31 "F.CrtYd" user "Package Geometry/Place Bound Top")
		(29 "B.CrtYd" user "Package Geometry/Place Bound Bottom")
		(35 "F.Fab" user "Ref Des/Assembly Top")
		(33 "B.Fab" user "Ref Des/Assembly Bottom")
	)
	(footprint ""
		(layer "F.Cu")
		(at 84.57565 -36.915598 -90)
		(property "Reference" "R5550"
			(at 0 0 270)
			(layer "F.SilkS")
			(hide yes)
			(effects
				(font
					(size 1.27 1.27)
				)
			)
		)
		(property "Value" ""
			(at 0 0 270)
			(layer "F.Fab")
			(effects
				(font
					(size 1.27 1.27)
				)
			)
		)
		(duplicate_pad_numbers_are_jumpers no)
		(fp_line
			(start -0.7874 0.4064)
			(end -0.7874 -0.4064)
			(stroke
				(width 0.1524)
				(type default)
			)
			(layer "F.SilkS")
		)
		(fp_line
			(start 0.7874 0.4064)
			(end -0.7874 0.4064)
			(stroke
				(width 0.1524)
				(type default)
			)
			(layer "F.SilkS")
		)
		(fp_line
			(start -0.7874 -0.4064)
			(end 0.7874 -0.4064)
			(stroke
				(width 0.1524)
				(type default)
			)
			(layer "F.SilkS")
		)
		(fp_line
			(start 0.7874 -0.4064)
			(end 0.7874 0.4064)
			(stroke
				(width 0.1524)
				(type default)
			)
			(layer "F.SilkS")
		)
		(fp_line
			(start -0.67945 0.3048)
			(end -0.67945 -0.305054)
			(stroke
				(width 0.1)
				(type default)
			)
			(layer "F.Fab")
		)
		(fp_line
			(start -0.12065 0.3048)
			(end -0.67945 0.3048)
			(stroke
				(width 0.1)
				(type default)
			)
			(layer "F.Fab")
		)
		(fp_line
			(start 0.120396 0.3048)
			(end 0.120396 0.2794)
			(stroke
				(width 0.1)
				(type default)
			)
			(layer "F.Fab")
		)
		(fp_line
			(start 0.67945 0.3048)
			(end 0.120396 0.3048)
			(stroke
				(width 0.1)
				(type default)
			)
			(layer "F.Fab")
		)
		(fp_line
			(start -0.12065 0.2794)
			(end -0.12065 0.3048)
			(stroke
				(width 0.1)
				(type default)
			)
			(layer "F.Fab")
		)
		(fp_line
			(start 0.120396 0.2794)
			(end -0.12065 0.2794)
			(stroke
				(width 0.1)
				(type default)
			)
			(layer "F.Fab")
		)
		(fp_line
			(start -0.12065 -0.2794)
			(end 0.12065 -0.2794)
			(stroke
				(width 0.1)
				(type default)
			)
			(layer "F.Fab")
		)
		(fp_line
			(start 0.12065 -0.2794)
			(end 0.12065 -0.3048)
			(stroke
				(width 0.1)
				(type default)
			)
			(layer "F.Fab")
		)
		(fp_line
			(start 0.12065 -0.3048)
			(end 0.67945 -0.3048)
			(stroke
				(width 0.1)
				(type default)
			)
			(layer "F.Fab")
		)
		(fp_line
			(start 0.67945 -0.3048)
			(end 0.67945 0.3048)
			(stroke
				(width 0.1)
				(type default)
			)
			(layer "F.Fab")
		)
		(fp_line
			(start -0.67945 -0.305054)
			(end -0.12065 -0.305054)
			(stroke
				(width 0.1)
				(type default)
			)
			(layer "F.Fab")
		)
		(fp_line
			(start -0.12065 -0.305054)
			(end -0.12065 -0.2794)
			(stroke
				(width 0.1)
				(type default)
			)
			(layer "F.Fab")
		)
		(pad "1" smd circle
			(at -0.40005 0 270)
			(size 0 0)
			(layers "F.Cu" "F.Mask" "F.Paste")
			(net "PRSNT_SSD3_R1_N")
		)
		(pad "2" smd circle
			(at 0.40005 0 270)
			(size 0 0)
			(layers "F.Cu" "F.Mask" "F.Paste")
			(net "PRSNT_SSD3_R_N")
		)
	)
	(footprint ""
		(layer "F.Cu")
		(at 241.624612 -62.617858 -90)
		(property "Reference" "R5992"
			(at 0 0 270)
			(layer "F.SilkS")
			(hide yes)
			(effects
				(font
					(size 1.27 1.27)
				)
			)
		)
		(property "Value" ""
			(at 0 0 270)
			(layer "F.Fab")
			(effects
				(font
					(size 1.27 1.27)
				)
			)
		)
		(duplicate_pad_numbers_are_jumpers no)
		(fp_line
			(start -0.7874 0.4064)
			(end -0.7874 -0.4064)
			(stroke
				(width 0.1524)
				(type default)
			)
			(layer "F.SilkS")
		)
		(fp_line
			(start 0.7874 0.4064)
			(end -0.7874 0.4064)
			(stroke
				(width 0.1524)
				(type default)
			)
			(layer "F.SilkS")
		)
		(fp_line
			(start -0.7874 -0.4064)
			(end 0.7874 -0.4064)
			(stroke
				(width 0.1524)
				(type default)
			)
			(layer "F.SilkS")
		)
		(fp_line
			(start 0.7874 -0.4064)
			(end 0.7874 0.4064)
			(stroke
				(width 0.1524)
				(type default)
			)
			(layer "F.SilkS")
		)
		(fp_line
			(start -0.67945 0.3048)
			(end -0.67945 -0.305054)
			(stroke
				(width 0.1)
				(type default)
			)
			(layer "F.Fab")
		)
		(fp_line
			(start -0.12065 0.3048)
			(end -0.67945 0.3048)
			(stroke
				(width 0.1)
				(type default)
			)
			(layer "F.Fab")
		)
		(fp_line
			(start 0.120396 0.3048)
			(end 0.120396 0.2794)
			(stroke
				(width 0.1)
				(type default)
			)
			(layer "F.Fab")
		)
		(fp_line
			(start 0.67945 0.3048)
			(end 0.120396 0.3048)
			(stroke
				(width 0.1)
				(type default)
			)
			(layer "F.Fab")
		)
		(fp_line
			(start -0.12065 0.2794)
			(end -0.12065 0.3048)
			(stroke
				(width 0.1)
				(type default)
			)
			(layer "F.Fab")
		)
		(fp_line
			(start 0.120396 0.2794)
			(end -0.12065 0.2794)
			(stroke
				(width 0.1)
				(type default)
			)
			(layer "F.Fab")
		)
		(fp_line
			(start -0.12065 -0.2794)
			(end 0.12065 -0.2794)
			(stroke
				(width 0.1)
				(type default)
			)
			(layer "F.Fab")
		)
		(fp_line
			(start 0.12065 -0.2794)
			(end 0.12065 -0.3048)
			(stroke
				(width 0.1)
				(type default)
			)
			(layer "F.Fab")
		)
		(fp_line
			(start 0.12065 -0.3048)
			(end 0.67945 -0.3048)
			(stroke
				(width 0.1)
				(type default)
			)
			(layer "F.Fab")
		)
		(fp_line
			(start 0.67945 -0.3048)
			(end 0.67945 0.3048)
			(stroke
				(width 0.1)
				(type default)
			)
			(layer "F.Fab")
		)
		(fp_line
			(start -0.67945 -0.305054)
			(end -0.12065 -0.305054)
			(stroke
				(width 0.1)
				(type default)
			)
			(layer "F.Fab")
		)
		(fp_line
			(start -0.12065 -0.305054)
			(end -0.12065 -0.2794)
			(stroke
				(width 0.1)
				(type default)
			)
			(layer "F.Fab")
		)
		(pad "1" smd circle
			(at -0.40005 0 270)
			(size 0 0)
			(layers "F.Cu" "F.Mask" "F.Paste")
			(net "P3V3_AUX")
		)
		(pad "2" smd circle
			(at 0.40005 0 270)
			(size 0 0)
			(layers "F.Cu" "F.Mask" "F.Paste")
			(net "PWRGD_P12V_SSD8_D")
		)
	)
	(footprint ""
		(layer "F.Cu")
		(at 197.102476 -89.1159)
		(property "Reference" "C902"
			(at 0 0 0)
			(layer "F.SilkS")
			(hide yes)
			(effects
				(font
					(size 1.27 1.27)
				)
			)
		)
		(property "Value" ""
			(at 0 0 0)
			(layer "F.Fab")
			(effects
				(font
					(size 1.27 1.27)
				)
			)
		)
		(duplicate_pad_numbers_are_jumpers no)
		(fp_line
			(start -0.7874 -0.4064)
			(end 0.7874 -0.4064)
			(stroke
				(width 0.1524)
				(type default)
			)
			(layer "F.SilkS")
		)
		(fp_line
			(start -0.7874 0.4064)
			(end -0.7874 -0.4064)
			(stroke
				(width 0.1524)
				(type default)
			)
			(layer "F.SilkS")
		)
		(fp_line
			(start 0.7874 -0.4064)
			(end 0.7874 0.4064)
			(stroke
				(width 0.1524)
				(type default)
			)
			(layer "F.SilkS")
		)
		(fp_line
			(start 0.7874 0.4064)
			(end -0.7874 0.4064)
			(stroke
				(width 0.1524)
				(type default)
			)
			(layer "F.SilkS")
		)
		(fp_line
			(start -0.67945 -0.305054)
			(end -0.12065 -0.305054)
			(stroke
				(width 0.1)
				(type default)
			)
			(layer "F.Fab")
		)
		(fp_line
			(start -0.67945 0.3048)
			(end -0.67945 -0.305054)
			(stroke
				(width 0.1)
				(type default)
			)
			(layer "F.Fab")
		)
		(fp_line
			(start -0.12065 -0.305054)
			(end -0.12065 -0.2794)
			(stroke
				(width 0.1)
				(type default)
			)
			(layer "F.Fab")
		)
		(fp_line
			(start -0.12065 -0.2794)
			(end 0.12065 -0.2794)
			(stroke
				(width 0.1)
				(type default)
			)
			(layer "F.Fab")
		)
		(fp_line
			(start -0.12065 0.2794)
			(end -0.12065 0.3048)
			(stroke
				(width 0.1)
				(type default)
			)
			(layer "F.Fab")
		)
		(fp_line
			(start -0.12065 0.3048)
			(end -0.67945 0.3048)
			(stroke
				(width 0.1)
				(type default)
			)
			(layer "F.Fab")
		)
		(fp_line
			(start 0.120396 0.2794)
			(end -0.12065 0.2794)
			(stroke
				(width 0.1)
				(type default)
			)
			(layer "F.Fab")
		)
		(fp_line
			(start 0.120396 0.3048)
			(end 0.120396 0.2794)
			(stroke
				(width 0.1)
				(type default)
			)
			(layer "F.Fab")
		)
		(fp_line
			(start 0.12065 -0.3048)
			(end 0.67945 -0.3048)
			(stroke
				(width 0.1)
				(type default)
			)
			(layer "F.Fab")
		)
		(fp_line
			(start 0.12065 -0.2794)
			(end 0.12065 -0.3048)
			(stroke
				(width 0.1)
				(type default)
			)
			(layer "F.Fab")
		)
		(fp_line
			(start 0.67945 -0.3048)
			(end 0.67945 0.3048)
			(stroke
				(width 0.1)
				(type default)
			)
			(layer "F.Fab")
		)
		(fp_line
			(start 0.67945 0.3048)
			(end 0.120396 0.3048)
			(stroke
				(width 0.1)
				(type default)
			)
			(layer "F.Fab")
		)
		(pad "1" smd circle
			(at -0.40005 0)
			(size 0 0)
			(layers "F.Cu" "F.Mask" "F.Paste")
			(net "P3V3_AUX")
		)
		(pad "2" smd circle
			(at 0.40005 0)
			(size 0 0)
			(layers "F.Cu" "F.Mask" "F.Paste")
			(net "GND")
		)
	)
	(footprint ""
		(layer "F.Cu")
		(at 366.566196 -282.421584 -90)
		(property "Reference" "PC194"
			(at 0 0 270)
			(layer "F.SilkS")
			(hide yes)
			(effects
				(font
					(size 1.27 1.27)
				)
			)
		)
		(property "Value" ""
			(at 0 0 270)
			(layer "F.Fab")
			(effects
				(font
					(size 1.27 1.27)
				)
			)
		)
		(duplicate_pad_numbers_are_jumpers no)
		(fp_line
			(start -0.7874 0.4064)
			(end -0.7874 -0.4064)
			(stroke
				(width 0.1524)
				(type default)
			)
			(layer "F.SilkS")
		)
		(fp_line
			(start 0.7874 0.4064)
			(end -0.7874 0.4064)
			(stroke
				(width 0.1524)
				(type default)
			)
			(layer "F.SilkS")
		)
		(fp_line
			(start -0.7874 -0.4064)
			(end 0.7874 -0.4064)
			(stroke
				(width 0.1524)
				(type default)
			)
			(layer "F.SilkS")
		)
		(fp_line
			(start 0.7874 -0.4064)
			(end 0.7874 0.4064)
			(stroke
				(width 0.1524)
				(type default)
			)
			(layer "F.SilkS")
		)
		(fp_line
			(start -0.67945 0.3048)
			(end -0.67945 -0.305054)
			(stroke
				(width 0.1)
				(type default)
			)
			(layer "F.Fab")
		)
		(fp_line
			(start -0.12065 0.3048)
			(end -0.67945 0.3048)
			(stroke
				(width 0.1)
				(type default)
			)
			(layer "F.Fab")
		)
		(fp_line
			(start 0.120396 0.3048)
			(end 0.120396 0.2794)
			(stroke
				(width 0.1)
				(type default)
			)
			(layer "F.Fab")
		)
		(fp_line
			(start 0.67945 0.3048)
			(end 0.120396 0.3048)
			(stroke
				(width 0.1)
				(type default)
			)
			(layer "F.Fab")
		)
		(fp_line
			(start -0.12065 0.2794)
			(end -0.12065 0.3048)
			(stroke
				(width 0.1)
				(type default)
			)
			(layer "F.Fab")
		)
		(fp_line
			(start 0.120396 0.2794)
			(end -0.12065 0.2794)
			(stroke
				(width 0.1)
				(type default)
			)
			(layer "F.Fab")
		)
		(fp_line
			(start -0.12065 -0.2794)
			(end 0.12065 -0.2794)
			(stroke
				(width 0.1)
				(type default)
			)
			(layer "F.Fab")
		)
		(fp_line
			(start 0.12065 -0.2794)
			(end 0.12065 -0.3048)
			(stroke
				(width 0.1)
				(type default)
			)
			(layer "F.Fab")
		)
		(fp_line
			(start 0.12065 -0.3048)
			(end 0.67945 -0.3048)
			(stroke
				(width 0.1)
				(type default)
			)
			(layer "F.Fab")
		)
		(fp_line
			(start 0.67945 -0.3048)
			(end 0.67945 0.3048)
			(stroke
				(width 0.1)
				(type default)
			)
			(layer "F.Fab")
		)
		(fp_line
			(start -0.67945 -0.305054)
			(end -0.12065 -0.305054)
			(stroke
				(width 0.1)
				(type default)
			)
			(layer "F.Fab")
		)
		(fp_line
			(start -0.12065 -0.305054)
			(end -0.12065 -0.2794)
			(stroke
				(width 0.1)
				(type default)
			)
			(layer "F.Fab")
		)
		(pad "1" smd circle
			(at -0.40005 0 270)
			(size 0 0)
			(layers "F.Cu" "F.Mask" "F.Paste")
			(net "P0V8_PEX3_VCC2")
		)
		(pad "2" smd circle
			(at 0.40005 0 270)
			(size 0 0)
			(layers "F.Cu" "F.Mask" "F.Paste")
			(net "GND")
		)
	)
	(footprint ""
		(layer "F.Cu")
		(at 38.7604 -116.7384)
		(property "Reference" "R39"
			(at 0 0 0)
			(layer "F.SilkS")
			(hide yes)
			(effects
				(font
					(size 1.27 1.27)
				)
			)
		)
		(property "Value" ""
			(at 0 0 0)
			(layer "F.Fab")
			(effects
				(font
					(size 1.27 1.27)
				)
			)
		)
		(duplicate_pad_numbers_are_jumpers no)
		(fp_line
			(start -0.7874 -0.4064)
			(end 0.7874 -0.4064)
			(stroke
				(width 0.1524)
				(type default)
			)
			(layer "F.SilkS")
		)
		(fp_line
			(start -0.7874 0.4064)
			(end -0.7874 -0.4064)
			(stroke
				(width 0.1524)
				(type default)
			)
			(layer "F.SilkS")
		)
		(fp_line
			(start 0.7874 -0.4064)
			(end 0.7874 0.4064)
			(stroke
				(width 0.1524)
				(type default)
			)
			(layer "F.SilkS")
		)
		(fp_line
			(start 0.7874 0.4064)
			(end -0.7874 0.4064)
			(stroke
				(width 0.1524)
				(type default)
			)
			(layer "F.SilkS")
		)
		(fp_line
			(start -0.67945 -0.305054)
			(end -0.12065 -0.305054)
			(stroke
				(width 0.1)
				(type default)
			)
			(layer "F.Fab")
		)
		(fp_line
			(start -0.67945 0.3048)
			(end -0.67945 -0.305054)
			(stroke
				(width 0.1)
				(type default)
			)
			(layer "F.Fab")
		)
		(fp_line
			(start -0.12065 -0.305054)
			(end -0.12065 -0.2794)
			(stroke
				(width 0.1)
				(type default)
			)
			(layer "F.Fab")
		)
		(fp_line
			(start -0.12065 -0.2794)
			(end 0.12065 -0.2794)
			(stroke
				(width 0.1)
				(type default)
			)
			(layer "F.Fab")
		)
		(fp_line
			(start -0.12065 0.2794)
			(end -0.12065 0.3048)
			(stroke
				(width 0.1)
				(type default)
			)
			(layer "F.Fab")
		)
		(fp_line
			(start -0.12065 0.3048)
			(end -0.67945 0.3048)
			(stroke
				(width 0.1)
				(type default)
			)
			(layer "F.Fab")
		)
		(fp_line
			(start 0.120396 0.2794)
			(end -0.12065 0.2794)
			(stroke
				(width 0.1)
				(type default)
			)
			(layer "F.Fab")
		)
		(fp_line
			(start 0.120396 0.3048)
			(end 0.120396 0.2794)
			(stroke
				(width 0.1)
				(type default)
			)
			(layer "F.Fab")
		)
		(fp_line
			(start 0.12065 -0.3048)
			(end 0.67945 -0.3048)
			(stroke
				(width 0.1)
				(type default)
			)
			(layer "F.Fab")
		)
		(fp_line
			(start 0.12065 -0.2794)
			(end 0.12065 -0.3048)
			(stroke
				(width 0.1)
				(type default)
			)
			(layer "F.Fab")
		)
		(fp_line
			(start 0.67945 -0.3048)
			(end 0.67945 0.3048)
			(stroke
				(width 0.1)
				(type default)
			)
			(layer "F.Fab")
		)
		(fp_line
			(start 0.67945 0.3048)
			(end 0.120396 0.3048)
			(stroke
				(width 0.1)
				(type default)
			)
			(layer "F.Fab")
		)
		(pad "1" smd circle
			(at -0.40005 0)
			(size 0 0)
			(layers "F.Cu" "F.Mask" "F.Paste")
			(net "PRSNT_NIC0_N")
		)
		(pad "2" smd circle
			(at 0.40005 0)
			(size 0 0)
			(layers "F.Cu" "F.Mask" "F.Paste")
			(net "PRSNTB0_NIC0_N")
		)
	)
	(footprint ""
		(layer "F.Cu")
		(at 115.860068 -343.952322 90)
		(property "Reference" "C359"
			(at 0 0 90)
			(layer "F.SilkS")
			(hide yes)
			(effects
				(font
					(size 1.27 1.27)
				)
			)
		)
		(property "Value" ""
			(at 0 0 90)
			(layer "F.Fab")
			(effects
				(font
					(size 1.27 1.27)
				)
			)
		)
		(duplicate_pad_numbers_are_jumpers no)
		(fp_line
			(start 0.299974 -0.150114)
			(end 0.299974 0.150114)
			(stroke
				(width 0.1)
				(type default)
			)
			(layer "F.Fab")
		)
		(fp_line
			(start -0.299974 -0.150114)
			(end 0.299974 -0.150114)
			(stroke
				(width 0.1)
				(type default)
			)
			(layer "F.Fab")
		)
		(fp_line
			(start 0.299974 0.150114)
			(end -0.299974 0.150114)
			(stroke
				(width 0.1)
				(type default)
			)
			(layer "F.Fab")
		)
		(fp_line
			(start -0.299974 0.150114)
			(end -0.299974 -0.150114)
			(stroke
				(width 0.1)
				(type default)
			)
			(layer "F.Fab")
		)
		(pad "1" smd rect
			(at -0.2667 0 90)
			(size 0.3048 0.381)
			(layers "F.Cu" "F.Mask" "F.Paste")
			(net "P5E_PEX1_STN6_TX_DN<102>")
		)
		(pad "2" smd rect
			(at 0.2667 0 90)
			(size 0.3048 0.381)
			(layers "F.Cu" "F.Mask" "F.Paste")
			(net "P5E_PEX1_STN6_TX_C_DN<102>")
		)
	)
	(footprint ""
		(layer "F.Cu")
		(at 330.859384 -61.612526)
		(property "Reference" "PD49"
			(at -3.7084 -2.733548 0)
			(unlocked yes)
			(layer "F.SilkS")
			(effects
				(font
					(size 0.7874 0.5842)
					(thickness 0.1524)
				)
				(justify left)
			)
		)
		(property "Value" ""
			(at 0 0 0)
			(layer "F.Fab")
			(effects
				(font
					(size 1.27 1.27)
				)
			)
		)
		(duplicate_pad_numbers_are_jumpers no)
		(fp_line
			(start -3.656584 -1.970024)
			(end -3.656584 1.970024)
			(stroke
				(width 0.1524)
				(type default)
			)
			(layer "F.SilkS")
		)
		(fp_line
			(start -3.656584 1.970024)
			(end 4.240784 1.970024)
			(stroke
				(width 0.1524)
				(type default)
			)
			(layer "F.SilkS")
		)
		(fp_line
			(start 4.240784 -1.970024)
			(end -3.656584 -1.970024)
			(stroke
				(width 0.1524)
				(type default)
			)
			(layer "F.SilkS")
		)
		(fp_line
			(start 4.240784 1.970024)
			(end 4.240784 -1.970024)
			(stroke
				(width 0.1524)
				(type default)
			)
			(layer "F.SilkS")
		)
		(fp_poly
			(pts
				(xy 3.580384 1.970024) (xy 3.580384 -1.970024) (xy 4.240784 -1.970024) (xy 4.240784 1.970024)
			)
			(stroke
				(width 0)
				(type default)
			)
			(fill yes)
			(layer "F.SilkS")
		)
		(fp_line
			(start -2.3749 -1.970024)
			(end -2.3749 1.970024)
			(stroke
				(width 0.1)
				(type default)
			)
			(layer "F.Fab")
		)
		(fp_line
			(start -2.3749 1.970024)
			(end 2.3749 1.970024)
			(stroke
				(width 0.1)
				(type default)
			)
			(layer "F.Fab")
		)
		(fp_line
			(start 2.3749 -1.970024)
			(end -2.3749 -1.970024)
			(stroke
				(width 0.1)
				(type default)
			)
			(layer "F.Fab")
		)
		(fp_line
			(start 2.3749 1.970024)
			(end 2.3749 -1.970024)
			(stroke
				(width 0.1)
				(type default)
			)
			(layer "F.Fab")
		)
		(fp_text user "+"
			(at -4.9784 -0.23495 0)
			(unlocked yes)
			(layer "F.Fab")
			(effects
				(font
					(size 1.905 1.4224)
					(thickness 0.1524)
				)
				(justify left)
			)
		)
		(fp_text user "-"
			(at 4.1656 -0.23495 0)
			(unlocked yes)
			(layer "F.Fab")
			(effects
				(font
					(size 1.905 1.4224)
					(thickness 0.1524)
				)
				(justify left)
			)
		)
		(pad "A" smd rect
			(at -2.450084 0)
			(size 2.159 2.2606)
			(layers "F.Cu" "F.Mask" "F.Paste")
			(net "GND")
		)
		(pad "C" smd rect
			(at 2.450084 0)
			(size 2.159 2.2606)
			(layers "F.Cu" "F.Mask" "F.Paste")
			(net "P12V_AUX")
		)
	)
)
